# BASEBOARD_FAB2 (Tioga Pass) — schematic netlist excerpt (pin names and nets, part order shuffled) for the footprints in the layout excerpt that follows; sources: Cadence DE-HDL packaged netlist, KiCad conversion of Wiwynn_Tioga_Pass_MB.brd

R2L11  RES  2.0K 1% CHIP  pkg 0402  page 178 : A = P3V3_STBY ; B = SGPIO_PCH_SATA_CLOCK_R
R8E27  RES  0.0 5% CHIP  pkg 0402  page 142 : A = FM_PE_M2_WAKE_N ; B = FM_ALL_WAKE_N

U8W2  NC7SB3157  IC  pkg SMLF  page 245
  B1  = JTAG_PLD_TDO
  GND  = GND
  B0  = JTAG_RISER_TDO_R
  A  = JTAG_PLD_TDO_MUX_R
  VCC  = P3V3_STBY
  S  = JTAG_RISER_N

(kicad_pcb
	(version 20260206)
	(generator "pcbnew")
	(generator_version "10.0")
	(general
		(thickness 1.6)
		(legacy_teardrops no)
	)
	(paper "A4")
	(title_block
		(title "Wiwynn_Tioga_Pass_MB.brd")
		(comment 1 "Tioga Pass / footprints 3884-3886 of 4770")
	)
	(layers
		(0 "F.Cu" signal "TOP")
		(4 "In1.Cu" signal "L2GND")
		(6 "In2.Cu" signal "L3")
		(8 "In3.Cu" signal "L4GND")
		(10 "In4.Cu" signal "L5")
		(12 "In5.Cu" signal "L6GND")
		(14 "In6.Cu" signal "L7VCC")
		(16 "In7.Cu" signal "L8VCC")
		(18 "In8.Cu" signal "L9GND")
		(20 "In9.Cu" signal "L10")
		(22 "In10.Cu" signal "L11GND")
		(24 "In11.Cu" signal "L12")
		(26 "In12.Cu" signal "L13GND")
		(2 "B.Cu" signal "BOTTOM")
		(9 "F.Adhes" user "F.Adhesive")
		(11 "B.Adhes" user "B.Adhesive")
		(13 "F.Paste" user "Package Geometry/Pastemask Top")
		(15 "B.Paste" user "Package Geometry/Pastemask Bottom")
		(5 "F.SilkS" user "Ref Des/Silkscreen Top")
		(7 "B.SilkS" user "Ref Des/Silkscreen Bottom")
		(1 "F.Mask" user "Board Geometry/Soldermask Top")
		(3 "B.Mask" user "Board Geometry/Soldermask Bottom")
		(17 "Dwgs.User" user "User.Drawings")
		(19 "Cmts.User" user "User.Comments")
		(21 "Eco1.User" user "User.Eco1")
		(23 "Eco2.User" user "User.Eco2")
		(25 "Edge.Cuts" user "Board Geometry/Outline")
		(27 "Margin" user)
		(31 "F.CrtYd" user "Package Geometry/Place Bound Top")
		(29 "B.CrtYd" user "Package Geometry/Place Bound Bottom")
		(35 "F.Fab" user "Ref Des/Assembly Top")
		(33 "B.Fab" user "Ref Des/Assembly Bottom")
	)
	(footprint ""
		(layer "B.Cu")
		(at 385.3688 -3.0988)
		(property "Reference" "U8W2"
			(at 0 -1.2065 0)
			(unlocked yes)
			(layer "B.SilkS")
			(effects
				(font
					(size 1.27 0.9652)
					(thickness 0.1524)
				)
				(justify left mirror)
			)
		)
		(property "Value" ""
			(at 0 0 0)
			(layer "B.Fab")
			(effects
				(font
					(size 1.27 1.27)
				)
				(justify mirror)
			)
		)
		(duplicate_pad_numbers_are_jumpers no)
		(fp_circle
			(center 0.848614 -0.6477)
			(end 0.975614 -0.6477)
			(stroke
				(width 0.254)
				(type default)
			)
			(fill no)
			(layer "B.SilkS")
		)
		(fp_poly
			(pts
				(xy -0.21463 -0.450088) (xy -1.56337 -0.450088) (xy -1.56337 1.75006) (xy -0.21463 1.75006)
			)
			(stroke
				(width 0)
				(type default)
			)
			(fill no)
			(layer "B.CrtYd")
		)
		(fp_line
			(start -1.56337 -0.450088)
			(end -1.56337 1.75006)
			(stroke
				(width 0.1)
				(type default)
			)
			(layer "B.Fab")
		)
		(fp_line
			(start -1.56337 1.75006)
			(end -0.21463 1.75006)
			(stroke
				(width 0.1)
				(type default)
			)
			(layer "B.Fab")
		)
		(fp_line
			(start -0.21463 -0.450088)
			(end -1.56337 -0.450088)
			(stroke
				(width 0.1)
				(type default)
			)
			(layer "B.Fab")
		)
		(fp_line
			(start -0.21463 1.75006)
			(end -0.21463 -0.450088)
			(stroke
				(width 0.1)
				(type default)
			)
			(layer "B.Fab")
		)
		(fp_circle
			(center 0.848614 -0.6477)
			(end 0.975614 -0.6477)
			(stroke
				(width 0.254)
				(type default)
			)
			(fill no)
			(layer "B.Fab")
		)
		(pad "1" smd rect
			(at 0 0 180)
			(size 1.016 0.381)
			(layers "B.Cu" "B.Mask" "B.Paste")
			(net "JTAG_PLD_TDO")
		)
		(pad "2" smd rect
			(at 0 0.649986 180)
			(size 1.016 0.381)
			(layers "B.Cu" "B.Mask" "B.Paste")
			(net "GND")
		)
		(pad "3" smd rect
			(at 0 1.299972 180)
			(size 1.016 0.381)
			(layers "B.Cu" "B.Mask" "B.Paste")
			(net "JTAG_RISER_TDO_R")
		)
		(pad "4" smd rect
			(at -1.778 1.299972 180)
			(size 1.016 0.381)
			(layers "B.Cu" "B.Mask" "B.Paste")
			(net "JTAG_PLD_TDO_MUX_R")
		)
		(pad "5" smd rect
			(at -1.778 0.649986 180)
			(size 1.016 0.381)
			(layers "B.Cu" "B.Mask" "B.Paste")
			(net "P3V3_STBY")
		)
		(pad "6" smd rect
			(at -1.778 0 180)
			(size 1.016 0.381)
			(layers "B.Cu" "B.Mask" "B.Paste")
			(net "JTAG_RISER_N")
		)
	)
	(footprint ""
		(layer "B.Cu")
		(at 482.65969 -57.307988 -90)
		(property "Reference" "R8E27"
			(at 0 0 90)
			(layer "B.SilkS")
			(hide yes)
			(effects
				(font
					(size 1.27 1.27)
				)
				(justify mirror)
			)
		)
		(property "Value" ""
			(at 0 0 90)
			(layer "B.Fab")
			(effects
				(font
					(size 1.27 1.27)
				)
				(justify mirror)
			)
		)
		(duplicate_pad_numbers_are_jumpers no)
		(fp_poly
			(pts
				(xy 0.2794 -0.1016) (xy -0.2794 -0.1016) (xy -0.2794 0.9906) (xy 0.2794 0.9906)
			)
			(stroke
				(width 0)
				(type default)
			)
			(fill no)
			(layer "B.CrtYd")
		)
		(fp_line
			(start -0.2794 0.9906)
			(end -0.2794 -0.1016)
			(stroke
				(width 0.1)
				(type default)
			)
			(layer "B.Fab")
		)
		(fp_line
			(start 0.2794 0.9906)
			(end -0.2794 0.9906)
			(stroke
				(width 0.1)
				(type default)
			)
			(layer "B.Fab")
		)
		(fp_line
			(start -0.2794 -0.1016)
			(end 0.2794 -0.1016)
			(stroke
				(width 0.1)
				(type default)
			)
			(layer "B.Fab")
		)
		(fp_line
			(start 0.2794 -0.1016)
			(end 0.2794 0.9906)
			(stroke
				(width 0.1)
				(type default)
			)
			(layer "B.Fab")
		)
		(pad "1" smd rect
			(at 0 0 90)
			(size 0.508 0.508)
			(layers "B.Cu" "B.Mask" "B.Paste")
			(net "FM_PE_M2_WAKE_N")
		)
		(pad "2" smd rect
			(at 0 0.889 90)
			(size 0.508 0.508)
			(layers "B.Cu" "B.Mask" "B.Paste")
			(net "FM_ALL_WAKE_N")
		)
		(zone
			(layer "B.Cu")
			(hatch none 0.5)
			(connect_pads
				(clearance 0)
			)
			(min_thickness 0.25)
			(keepout
				(tracks not_allowed)
				(vias allowed)
				(pads allowed)
				(copperpour not_allowed)
				(footprints allowed)
			)
			(placement
				(enabled no)
				(sheetname "")
			)
			(fill
				(thermal_gap 0.5)
				(thermal_bridge_width 0.5)
				(island_removal_mode 0)
			)
			(polygon
				(pts
					(xy 482.02469 -57.053988) (xy 482.02469 -57.561988) (xy 482.40569 -57.561988) (xy 482.40569 -57.053988)
				)
			)
		)
		(zone
			(layer "B.Cu")
			(hatch none 0.5)
			(connect_pads
				(clearance 0)
			)
			(min_thickness 0.25)
			(keepout
				(tracks allowed)
				(vias not_allowed)
				(pads allowed)
				(copperpour not_allowed)
				(footprints allowed)
			)
			(placement
				(enabled no)
				(sheetname "")
			)
			(fill
				(thermal_gap 0.5)
				(thermal_bridge_width 0.5)
				(island_removal_mode 0)
			)
			(polygon
				(pts
					(xy 482.40569 -57.053988) (xy 482.40569 -57.561988) (xy 482.02469 -57.561988) (xy 482.02469 -57.053988)
				)
			)
		)
	)
	(footprint ""
		(layer "B.Cu")
		(at 433.578 -153.543 -90)
		(property "Reference" "R2L11"
			(at 0 0 90)
			(layer "B.SilkS")
			(hide yes)
			(effects
				(font
					(size 1.27 1.27)
				)
				(justify mirror)
			)
		)
		(property "Value" ""
			(at 0 0 90)
			(layer "B.Fab")
			(effects
				(font
					(size 1.27 1.27)
				)
				(justify mirror)
			)
		)
		(duplicate_pad_numbers_are_jumpers no)
		(fp_poly
			(pts
				(xy 0.2794 -0.1016) (xy -0.2794 -0.1016) (xy -0.2794 0.9906) (xy 0.2794 0.9906)
			)
			(stroke
				(width 0)
				(type default)
			)
			(fill no)
			(layer "B.CrtYd")
		)
		(fp_line
			(start -0.2794 0.9906)
			(end -0.2794 -0.1016)
			(stroke
				(width 0.1)
				(type default)
			)
			(layer "B.Fab")
		)
		(fp_line
			(start 0.2794 0.9906)
			(end -0.2794 0.9906)
			(stroke
				(width 0.1)
				(type default)
			)
			(layer "B.Fab")
		)
		(fp_line
			(start -0.2794 -0.1016)
			(end 0.2794 -0.1016)
			(stroke
				(width 0.1)
				(type default)
			)
			(layer "B.Fab")
		)
		(fp_line
			(start 0.2794 -0.1016)
			(end 0.2794 0.9906)
			(stroke
				(width 0.1)
				(type default)
			)
			(layer "B.Fab")
		)
		(pad "1" smd rect
			(at 0 0 90)
			(size 0.508 0.508)
			(layers "B.Cu" "B.Mask" "B.Paste")
			(net "P3V3_STBY")
		)
		(pad "2" smd rect
			(at 0 0.889 90)
			(size 0.508 0.508)
			(layers "B.Cu" "B.Mask" "B.Paste")
			(net "SGPIO_PCH_SATA_CLOCK_R")
		)
		(zone
			(layer "B.Cu")
			(hatch none 0.5)
			(connect_pads
				(clearance 0)
			)
			(min_thickness 0.25)
			(keepout
				(tracks not_allowed)
				(vias allowed)
				(pads allowed)
				(copperpour not_allowed)
				(footprints allowed)
			)
			(placement
				(enabled no)
				(sheetname "")
			)
			(fill
				(thermal_gap 0.5)
				(thermal_bridge_width 0.5)
				(island_removal_mode 0)
			)
			(polygon
				(pts
					(xy 432.943 -153.289) (xy 432.943 -153.797) (xy 433.324 -153.797) (xy 433.324 -153.289)
				)
			)
		)
		(zone
			(layer "B.Cu")
			(hatch none 0.5)
			(connect_pads
				(clearance 0)
			)
			(min_thickness 0.25)
			(keepout
				(tracks allowed)
				(vias not_allowed)
				(pads allowed)
				(copperpour not_allowed)
				(footprints allowed)
			)
			(placement
				(enabled no)
				(sheetname "")
			)
			(fill
				(thermal_gap 0.5)
				(thermal_bridge_width 0.5)
				(island_removal_mode 0)
			)
			(polygon
				(pts
					(xy 433.324 -153.289) (xy 433.324 -153.797) (xy 432.943 -153.797) (xy 432.943 -153.289)
				)
			)
		)
	)
)
